(kicad_pcb
	(version 20260206)
	(generator "pcbnew")
	(generator_version "10.0")
	(general
		(thickness 1.6)
		(legacy_teardrops no)
	)
	(paper "A4")
	(title_block
		(title "03242023_DA0F0TMBIJ0_F0T_Motherboard_J_brd_V01_OCP.brd")
		(comment 1 "Grand Teton / footprints 1554-1559 of 6105")
	)
	(layers
		(0 "F.Cu" signal "TOP")
		(4 "In1.Cu" signal "GND")
		(6 "In2.Cu" signal "IN1")
		(8 "In3.Cu" signal "GND1")
		(10 "In4.Cu" signal "IN2")
		(12 "In5.Cu" signal "GND2")
		(14 "In6.Cu" signal "IN3")
		(16 "In7.Cu" signal "GND3")
		(18 "In8.Cu" signal "VCC")
		(20 "In9.Cu" signal "VCC1")
		(22 "In10.Cu" signal "GND4")
		(24 "In11.Cu" signal "IN4")
		(26 "In12.Cu" signal "GND5")
		(28 "In13.Cu" signal "IN5")
		(30 "In14.Cu" signal "GND6")
		(32 "In15.Cu" signal "IN6")
		(34 "In16.Cu" signal "GND7")
		(2 "B.Cu" signal "BOTTOM")
		(9 "F.Adhes" user "F.Adhesive")
		(11 "B.Adhes" user "B.Adhesive")
		(13 "F.Paste" user "Package Geometry/Pastemask Top")
		(15 "B.Paste" user "Package Geometry/Pastemask Bottom")
		(5 "F.SilkS" user "Ref Des/Silkscreen Top")
		(7 "B.SilkS" user "Ref Des/Silkscreen Bottom")
		(1 "F.Mask" user "Board Geometry/Soldermask Top")
		(3 "B.Mask" user "Board Geometry/Soldermask Bottom")
		(17 "Dwgs.User" user "User.Drawings")
		(19 "Cmts.User" user "User.Comments")
		(21 "Eco1.User" user "User.Eco1")
		(23 "Eco2.User" user "User.Eco2")
		(25 "Edge.Cuts" user "Board Geometry/Outline")
		(27 "Margin" user)
		(31 "F.CrtYd" user "Package Geometry/Place Bound Top")
		(29 "B.CrtYd" user "Package Geometry/Place Bound Bottom")
		(35 "F.Fab" user "Ref Des/Assembly Top")
		(33 "B.Fab" user "Ref Des/Assembly Bottom")
	)
	(footprint ""
		(layer "F.Cu")
		(at 170.23588 -437.987948)
		(property "Reference" "R3390"
			(at 0 0 0)
			(layer "F.SilkS")
			(hide yes)
			(effects
				(font
					(size 1.27 1.27)
				)
			)
		)
		(property "Value" ""
			(at 0 0 0)
			(layer "F.Fab")
			(effects
				(font
					(size 1.27 1.27)
				)
			)
		)
		(duplicate_pad_numbers_are_jumpers no)
		(fp_line
			(start -0.7874 -0.4064)
			(end 0.7874 -0.4064)
			(stroke
				(width 0.1524)
				(type default)
			)
			(layer "F.SilkS")
		)
		(fp_line
			(start -0.7874 0.4064)
			(end -0.7874 -0.4064)
			(stroke
				(width 0.1524)
				(type default)
			)
			(layer "F.SilkS")
		)
		(fp_line
			(start 0.7874 -0.4064)
			(end 0.7874 0.4064)
			(stroke
				(width 0.1524)
				(type default)
			)
			(layer "F.SilkS")
		)
		(fp_line
			(start 0.7874 0.4064)
			(end -0.7874 0.4064)
			(stroke
				(width 0.1524)
				(type default)
			)
			(layer "F.SilkS")
		)
		(fp_line
			(start -0.67945 -0.305054)
			(end -0.12065 -0.305054)
			(stroke
				(width 0.1)
				(type default)
			)
			(layer "F.Fab")
		)
		(fp_line
			(start -0.67945 0.3048)
			(end -0.67945 -0.305054)
			(stroke
				(width 0.1)
				(type default)
			)
			(layer "F.Fab")
		)
		(fp_line
			(start -0.12065 -0.305054)
			(end -0.12065 -0.2794)
			(stroke
				(width 0.1)
				(type default)
			)
			(layer "F.Fab")
		)
		(fp_line
			(start -0.12065 -0.2794)
			(end 0.12065 -0.2794)
			(stroke
				(width 0.1)
				(type default)
			)
			(layer "F.Fab")
		)
		(fp_line
			(start -0.12065 0.2794)
			(end -0.12065 0.3048)
			(stroke
				(width 0.1)
				(type default)
			)
			(layer "F.Fab")
		)
		(fp_line
			(start -0.12065 0.3048)
			(end -0.67945 0.3048)
			(stroke
				(width 0.1)
				(type default)
			)
			(layer "F.Fab")
		)
		(fp_line
			(start 0.120396 0.2794)
			(end -0.12065 0.2794)
			(stroke
				(width 0.1)
				(type default)
			)
			(layer "F.Fab")
		)
		(fp_line
			(start 0.120396 0.3048)
			(end 0.120396 0.2794)
			(stroke
				(width 0.1)
				(type default)
			)
			(layer "F.Fab")
		)
		(fp_line
			(start 0.12065 -0.3048)
			(end 0.67945 -0.3048)
			(stroke
				(width 0.1)
				(type default)
			)
			(layer "F.Fab")
		)
		(fp_line
			(start 0.12065 -0.2794)
			(end 0.12065 -0.3048)
			(stroke
				(width 0.1)
				(type default)
			)
			(layer "F.Fab")
		)
		(fp_line
			(start 0.67945 -0.3048)
			(end 0.67945 0.3048)
			(stroke
				(width 0.1)
				(type default)
			)
			(layer "F.Fab")
		)
		(fp_line
			(start 0.67945 0.3048)
			(end 0.120396 0.3048)
			(stroke
				(width 0.1)
				(type default)
			)
			(layer "F.Fab")
		)
		(pad "1" smd circle
			(at -0.40005 0)
			(size 0 0)
			(layers "F.Cu" "F.Mask" "F.Paste")
			(net "GPU_FPGA_BOOT_EN_BUF_R")
		)
		(pad "2" smd circle
			(at 0.40005 0)
			(size 0 0)
			(layers "F.Cu" "F.Mask" "F.Paste")
			(net "GPU_FPGA_BOOT_EN_BUF")
		)
	)
	(footprint ""
		(layer "F.Cu")
		(at 374.032018 -16.34617 180)
		(property "Reference" "R4601"
			(at 0 0 180)
			(layer "F.SilkS")
			(hide yes)
			(effects
				(font
					(size 1.27 1.27)
				)
			)
		)
		(property "Value" ""
			(at 0 0 180)
			(layer "F.Fab")
			(effects
				(font
					(size 1.27 1.27)
				)
			)
		)
		(duplicate_pad_numbers_are_jumpers no)
		(fp_line
			(start 0.7874 0.4064)
			(end -0.7874 0.4064)
			(stroke
				(width 0.1524)
				(type default)
			)
			(layer "F.SilkS")
		)
		(fp_line
			(start 0.7874 -0.4064)
			(end 0.7874 0.4064)
			(stroke
				(width 0.1524)
				(type default)
			)
			(layer "F.SilkS")
		)
		(fp_line
			(start -0.7874 0.4064)
			(end -0.7874 -0.4064)
			(stroke
				(width 0.1524)
				(type default)
			)
			(layer "F.SilkS")
		)
		(fp_line
			(start -0.7874 -0.4064)
			(end 0.7874 -0.4064)
			(stroke
				(width 0.1524)
				(type default)
			)
			(layer "F.SilkS")
		)
		(fp_line
			(start 0.67945 0.3048)
			(end 0.120396 0.3048)
			(stroke
				(width 0.1)
				(type default)
			)
			(layer "F.Fab")
		)
		(fp_line
			(start 0.67945 -0.3048)
			(end 0.67945 0.3048)
			(stroke
				(width 0.1)
				(type default)
			)
			(layer "F.Fab")
		)
		(fp_line
			(start 0.12065 -0.2794)
			(end 0.12065 -0.3048)
			(stroke
				(width 0.1)
				(type default)
			)
			(layer "F.Fab")
		)
		(fp_line
			(start 0.12065 -0.3048)
			(end 0.67945 -0.3048)
			(stroke
				(width 0.1)
				(type default)
			)
			(layer "F.Fab")
		)
		(fp_line
			(start 0.120396 0.3048)
			(end 0.120396 0.2794)
			(stroke
				(width 0.1)
				(type default)
			)
			(layer "F.Fab")
		)
		(fp_line
			(start 0.120396 0.2794)
			(end -0.12065 0.2794)
			(stroke
				(width 0.1)
				(type default)
			)
			(layer "F.Fab")
		)
		(fp_line
			(start -0.12065 0.3048)
			(end -0.67945 0.3048)
			(stroke
				(width 0.1)
				(type default)
			)
			(layer "F.Fab")
		)
		(fp_line
			(start -0.12065 0.2794)
			(end -0.12065 0.3048)
			(stroke
				(width 0.1)
				(type default)
			)
			(layer "F.Fab")
		)
		(fp_line
			(start -0.12065 -0.2794)
			(end 0.12065 -0.2794)
			(stroke
				(width 0.1)
				(type default)
			)
			(layer "F.Fab")
		)
		(fp_line
			(start -0.12065 -0.305054)
			(end -0.12065 -0.2794)
			(stroke
				(width 0.1)
				(type default)
			)
			(layer "F.Fab")
		)
		(fp_line
			(start -0.67945 0.3048)
			(end -0.67945 -0.305054)
			(stroke
				(width 0.1)
				(type default)
			)
			(layer "F.Fab")
		)
		(fp_line
			(start -0.67945 -0.305054)
			(end -0.12065 -0.305054)
			(stroke
				(width 0.1)
				(type default)
			)
			(layer "F.Fab")
		)
		(pad "1" smd circle
			(at -0.40005 0 180)
			(size 0 0)
			(layers "F.Cu" "F.Mask" "F.Paste")
			(net "CLK_50M_NCSI_OCP_SFF_ISO")
		)
		(pad "2" smd circle
			(at 0.40005 0 180)
			(size 0 0)
			(layers "F.Cu" "F.Mask" "F.Paste")
			(net "CLK_50M_NCSI_OCP_SFF_ISO_R")
		)
	)
	(footprint ""
		(layer "F.Cu")
		(at 323.815456 -27.612848 90)
		(property "Reference" "R2966"
			(at 0 0 90)
			(layer "F.SilkS")
			(hide yes)
			(effects
				(font
					(size 1.27 1.27)
				)
			)
		)
		(property "Value" ""
			(at 0 0 90)
			(layer "F.Fab")
			(effects
				(font
					(size 1.27 1.27)
				)
			)
		)
		(duplicate_pad_numbers_are_jumpers no)
		(fp_line
			(start 0.7874 -0.4064)
			(end 0.7874 0.4064)
			(stroke
				(width 0.1524)
				(type default)
			)
			(layer "F.SilkS")
		)
		(fp_line
			(start -0.7874 -0.4064)
			(end 0.7874 -0.4064)
			(stroke
				(width 0.1524)
				(type default)
			)
			(layer "F.SilkS")
		)
		(fp_line
			(start 0.7874 0.4064)
			(end -0.7874 0.4064)
			(stroke
				(width 0.1524)
				(type default)
			)
			(layer "F.SilkS")
		)
		(fp_line
			(start -0.7874 0.4064)
			(end -0.7874 -0.4064)
			(stroke
				(width 0.1524)
				(type default)
			)
			(layer "F.SilkS")
		)
		(fp_line
			(start -0.12065 -0.305054)
			(end -0.12065 -0.2794)
			(stroke
				(width 0.1)
				(type default)
			)
			(layer "F.Fab")
		)
		(fp_line
			(start -0.67945 -0.305054)
			(end -0.12065 -0.305054)
			(stroke
				(width 0.1)
				(type default)
			)
			(layer "F.Fab")
		)
		(fp_line
			(start 0.67945 -0.3048)
			(end 0.67945 0.3048)
			(stroke
				(width 0.1)
				(type default)
			)
			(layer "F.Fab")
		)
		(fp_line
			(start 0.12065 -0.3048)
			(end 0.67945 -0.3048)
			(stroke
				(width 0.1)
				(type default)
			)
			(layer "F.Fab")
		)
		(fp_line
			(start 0.12065 -0.2794)
			(end 0.12065 -0.3048)
			(stroke
				(width 0.1)
				(type default)
			)
			(layer "F.Fab")
		)
		(fp_line
			(start -0.12065 -0.2794)
			(end 0.12065 -0.2794)
			(stroke
				(width 0.1)
				(type default)
			)
			(layer "F.Fab")
		)
		(fp_line
			(start 0.120396 0.2794)
			(end -0.12065 0.2794)
			(stroke
				(width 0.1)
				(type default)
			)
			(layer "F.Fab")
		)
		(fp_line
			(start -0.12065 0.2794)
			(end -0.12065 0.3048)
			(stroke
				(width 0.1)
				(type default)
			)
			(layer "F.Fab")
		)
		(fp_line
			(start 0.67945 0.3048)
			(end 0.120396 0.3048)
			(stroke
				(width 0.1)
				(type default)
			)
			(layer "F.Fab")
		)
		(fp_line
			(start 0.120396 0.3048)
			(end 0.120396 0.2794)
			(stroke
				(width 0.1)
				(type default)
			)
			(layer "F.Fab")
		)
		(fp_line
			(start -0.12065 0.3048)
			(end -0.67945 0.3048)
			(stroke
				(width 0.1)
				(type default)
			)
			(layer "F.Fab")
		)
		(fp_line
			(start -0.67945 0.3048)
			(end -0.67945 -0.305054)
			(stroke
				(width 0.1)
				(type default)
			)
			(layer "F.Fab")
		)
		(pad "1" smd circle
			(at -0.40005 0 90)
			(size 0 0)
			(layers "F.Cu" "F.Mask" "F.Paste")
			(net "P3V3_RTC_AUX")
		)
		(pad "2" smd circle
			(at 0.40005 0 90)
			(size 0 0)
			(layers "F.Cu" "F.Mask" "F.Paste")
			(net "FM_INTRUDER_HDR_PCH_N")
		)
	)
	(footprint ""
		(layer "F.Cu")
		(at 205.6384 -97.6884 -90)
		(property "Reference" "R4778"
			(at 0 0 270)
			(layer "F.SilkS")
			(hide yes)
			(effects
				(font
					(size 1.27 1.27)
				)
			)
		)
		(property "Value" ""
			(at 0 0 270)
			(layer "F.Fab")
			(effects
				(font
					(size 1.27 1.27)
				)
			)
		)
		(duplicate_pad_numbers_are_jumpers no)
		(fp_line
			(start -0.7874 0.4064)
			(end -0.7874 -0.4064)
			(stroke
				(width 0.1524)
				(type default)
			)
			(layer "F.SilkS")
		)
		(fp_line
			(start 0.7874 0.4064)
			(end -0.7874 0.4064)
			(stroke
				(width 0.1524)
				(type default)
			)
			(layer "F.SilkS")
		)
		(fp_line
			(start -0.7874 -0.4064)
			(end 0.7874 -0.4064)
			(stroke
				(width 0.1524)
				(type default)
			)
			(layer "F.SilkS")
		)
		(fp_line
			(start 0.7874 -0.4064)
			(end 0.7874 0.4064)
			(stroke
				(width 0.1524)
				(type default)
			)
			(layer "F.SilkS")
		)
		(fp_line
			(start -0.67945 0.3048)
			(end -0.67945 -0.305054)
			(stroke
				(width 0.1)
				(type default)
			)
			(layer "F.Fab")
		)
		(fp_line
			(start -0.12065 0.3048)
			(end -0.67945 0.3048)
			(stroke
				(width 0.1)
				(type default)
			)
			(layer "F.Fab")
		)
		(fp_line
			(start 0.120396 0.3048)
			(end 0.120396 0.2794)
			(stroke
				(width 0.1)
				(type default)
			)
			(layer "F.Fab")
		)
		(fp_line
			(start 0.67945 0.3048)
			(end 0.120396 0.3048)
			(stroke
				(width 0.1)
				(type default)
			)
			(layer "F.Fab")
		)
		(fp_line
			(start -0.12065 0.2794)
			(end -0.12065 0.3048)
			(stroke
				(width 0.1)
				(type default)
			)
			(layer "F.Fab")
		)
		(fp_line
			(start 0.120396 0.2794)
			(end -0.12065 0.2794)
			(stroke
				(width 0.1)
				(type default)
			)
			(layer "F.Fab")
		)
		(fp_line
			(start -0.12065 -0.2794)
			(end 0.12065 -0.2794)
			(stroke
				(width 0.1)
				(type default)
			)
			(layer "F.Fab")
		)
		(fp_line
			(start 0.12065 -0.2794)
			(end 0.12065 -0.3048)
			(stroke
				(width 0.1)
				(type default)
			)
			(layer "F.Fab")
		)
		(fp_line
			(start 0.12065 -0.3048)
			(end 0.67945 -0.3048)
			(stroke
				(width 0.1)
				(type default)
			)
			(layer "F.Fab")
		)
		(fp_line
			(start 0.67945 -0.3048)
			(end 0.67945 0.3048)
			(stroke
				(width 0.1)
				(type default)
			)
			(layer "F.Fab")
		)
		(fp_line
			(start -0.67945 -0.305054)
			(end -0.12065 -0.305054)
			(stroke
				(width 0.1)
				(type default)
			)
			(layer "F.Fab")
		)
		(fp_line
			(start -0.12065 -0.305054)
			(end -0.12065 -0.2794)
			(stroke
				(width 0.1)
				(type default)
			)
			(layer "F.Fab")
		)
		(pad "1" smd circle
			(at -0.40005 0 270)
			(size 0 0)
			(layers "F.Cu" "F.Mask" "F.Paste")
			(net "P12V_AUX_UV_ADR_TRIGGER")
		)
		(pad "2" smd circle
			(at 0.40005 0 270)
			(size 0 0)
			(layers "F.Cu" "F.Mask" "F.Paste")
			(net "FM_UV_ADR_TRIGGER_N_R2")
		)
	)
	(footprint ""
		(layer "F.Cu")
		(at 202.7936 -92.6338 90)
		(property "Reference" "R4772"
			(at 0 0 90)
			(layer "F.SilkS")
			(hide yes)
			(effects
				(font
					(size 1.27 1.27)
				)
			)
		)
		(property "Value" ""
			(at 0 0 90)
			(layer "F.Fab")
			(effects
				(font
					(size 1.27 1.27)
				)
			)
		)
		(duplicate_pad_numbers_are_jumpers no)
		(fp_line
			(start 0.7874 -0.4064)
			(end 0.7874 0.4064)
			(stroke
				(width 0.1524)
				(type default)
			)
			(layer "F.SilkS")
		)
		(fp_line
			(start -0.7874 -0.4064)
			(end 0.7874 -0.4064)
			(stroke
				(width 0.1524)
				(type default)
			)
			(layer "F.SilkS")
		)
		(fp_line
			(start 0.7874 0.4064)
			(end -0.7874 0.4064)
			(stroke
				(width 0.1524)
				(type default)
			)
			(layer "F.SilkS")
		)
		(fp_line
			(start -0.7874 0.4064)
			(end -0.7874 -0.4064)
			(stroke
				(width 0.1524)
				(type default)
			)
			(layer "F.SilkS")
		)
		(fp_line
			(start -0.12065 -0.305054)
			(end -0.12065 -0.2794)
			(stroke
				(width 0.1)
				(type default)
			)
			(layer "F.Fab")
		)
		(fp_line
			(start -0.67945 -0.305054)
			(end -0.12065 -0.305054)
			(stroke
				(width 0.1)
				(type default)
			)
			(layer "F.Fab")
		)
		(fp_line
			(start 0.67945 -0.3048)
			(end 0.67945 0.3048)
			(stroke
				(width 0.1)
				(type default)
			)
			(layer "F.Fab")
		)
		(fp_line
			(start 0.12065 -0.3048)
			(end 0.67945 -0.3048)
			(stroke
				(width 0.1)
				(type default)
			)
			(layer "F.Fab")
		)
		(fp_line
			(start 0.12065 -0.2794)
			(end 0.12065 -0.3048)
			(stroke
				(width 0.1)
				(type default)
			)
			(layer "F.Fab")
		)
		(fp_line
			(start -0.12065 -0.2794)
			(end 0.12065 -0.2794)
			(stroke
				(width 0.1)
				(type default)
			)
			(layer "F.Fab")
		)
		(fp_line
			(start 0.120396 0.2794)
			(end -0.12065 0.2794)
			(stroke
				(width 0.1)
				(type default)
			)
			(layer "F.Fab")
		)
		(fp_line
			(start -0.12065 0.2794)
			(end -0.12065 0.3048)
			(stroke
				(width 0.1)
				(type default)
			)
			(layer "F.Fab")
		)
		(fp_line
			(start 0.67945 0.3048)
			(end 0.120396 0.3048)
			(stroke
				(width 0.1)
				(type default)
			)
			(layer "F.Fab")
		)
		(fp_line
			(start 0.120396 0.3048)
			(end 0.120396 0.2794)
			(stroke
				(width 0.1)
				(type default)
			)
			(layer "F.Fab")
		)
		(fp_line
			(start -0.12065 0.3048)
			(end -0.67945 0.3048)
			(stroke
				(width 0.1)
				(type default)
			)
			(layer "F.Fab")
		)
		(fp_line
			(start -0.67945 0.3048)
			(end -0.67945 -0.305054)
			(stroke
				(width 0.1)
				(type default)
			)
			(layer "F.Fab")
		)
		(pad "1" smd circle
			(at -0.40005 0 90)
			(size 0 0)
			(layers "F.Cu" "F.Mask" "F.Paste")
			(net "P3V3_AUX")
		)
		(pad "2" smd circle
			(at 0.40005 0 90)
			(size 0 0)
			(layers "F.Cu" "F.Mask" "F.Paste")
			(net "UV_ADR_P2V5_COMP")
		)
	)
	(footprint ""
		(layer "F.Cu")
		(at 369.6208 -16.271748 180)
		(property "Reference" "U320"
			(at 1.64338 -2.461768 0)
			(unlocked yes)
			(layer "F.SilkS")
			(effects
				(font
					(size 0.7874 0.5842)
					(thickness 0.1524)
				)
				(justify left)
			)
		)
		(property "Value" ""
			(at 0 0 180)
			(layer "F.Fab")
			(effects
				(font
					(size 1.27 1.27)
				)
			)
		)
		(duplicate_pad_numbers_are_jumpers no)
		(fp_line
			(start 2.032 1.549908)
			(end -2.032 1.549908)
			(stroke
				(width 0.1524)
				(type default)
			)
			(layer "F.SilkS")
		)
		(fp_line
			(start 2.032 -1.549908)
			(end 2.032 1.549908)
			(stroke
				(width 0.1524)
				(type default)
			)
			(layer "F.SilkS")
		)
		(fp_line
			(start -2.032 1.549908)
			(end -2.032 -1.549908)
			(stroke
				(width 0.1524)
				(type default)
			)
			(layer "F.SilkS")
		)
		(fp_line
			(start -2.032 -1.549908)
			(end 2.032 -1.549908)
			(stroke
				(width 0.1524)
				(type default)
			)
			(layer "F.SilkS")
		)
		(fp_poly
			(pts
				(xy -2.629408 -2.512568) (xy -2.988564 -2.153412) (xy -2.270252 -1.794002)
			)
			(stroke
				(width 0)
				(type default)
			)
			(fill yes)
			(layer "F.SilkS")
		)
		(fp_line
			(start 0.849884 1.549908)
			(end 0.849884 -1.549908)
			(stroke
				(width 0.1)
				(type default)
			)
			(layer "F.Fab")
		)
		(fp_line
			(start 0.849884 -1.549908)
			(end -0.849884 -1.549908)
			(stroke
				(width 0.1)
				(type default)
			)
			(layer "F.Fab")
		)
		(fp_line
			(start -0.849884 1.549908)
			(end 0.849884 1.549908)
			(stroke
				(width 0.1)
				(type default)
			)
			(layer "F.Fab")
		)
		(fp_line
			(start -0.849884 -1.549908)
			(end -0.849884 1.549908)
			(stroke
				(width 0.1)
				(type default)
			)
			(layer "F.Fab")
		)
		(fp_poly
			(pts
				(xy -2.9464 -1.2192) (xy -2.9464 -0.7112) (xy -2.1844 -0.9652)
			)
			(stroke
				(width 0)
				(type default)
			)
			(fill yes)
			(layer "F.Fab")
		)
		(pad "1" smd rect
			(at -1.225042 -0.94996 90)
			(size 0.4572 1.3208)
			(layers "F.Cu" "F.Mask" "F.Paste")
			(net "CLK_50M_NCSI_OCP_SFF")
		)
		(pad "2" smd rect
			(at -1.225042 0 90)
			(size 0.4572 1.3208)
			(layers "F.Cu" "F.Mask" "F.Paste")
			(net "CLK_50M_NCSI_OCP_SFF_ISO_R")
		)
		(pad "3" smd rect
			(at -1.225042 0.94996 90)
			(size 0.4572 1.3208)
			(layers "F.Cu" "F.Mask" "F.Paste")
			(net "GND")
		)
		(pad "4" smd rect
			(at 1.225042 0.94996 90)
			(size 0.4572 1.3208)
			(layers "F.Cu" "F.Mask" "F.Paste")
			(net "FB_BMC_ISOLATE")
		)
		(pad "5" smd rect
			(at 1.225042 -0.94996 90)
			(size 0.4572 1.3208)
			(layers "F.Cu" "F.Mask" "F.Paste")
			(net "P3V3_AUX")
		)
	)
)
